# BASEBOARD_FAB2 (Tioga Pass) — schematic netlist excerpt (pin names and nets, part order shuffled) for the footprints in the layout excerpt that follows; sources: Cadence DE-HDL packaged netlist, KiCad conversion of Wiwynn_Tioga_Pass_MB.brd

C2U19  CAP_A  0.1UF 16V 10% X7R  pkg 0402V  page 198 : A = P3V3 ; B = GND
R2U27  RES  0.0 5% CHIP  pkg 0402  page 107 : A = P3E_CPU0_PE1_SS_RXN<6> ; B = P3E_CPU0_PE1_SS_R_RXN<6>

(kicad_pcb
	(version 20260206)
	(generator "pcbnew")
	(generator_version "10.0")
	(general
		(thickness 1.6)
		(legacy_teardrops no)
	)
	(paper "A4")
	(title_block
		(title "Wiwynn_Tioga_Pass_MB.brd")
		(comment 1 "Tioga Pass / footprints 2385-2386 of 4770")
	)
	(layers
		(0 "F.Cu" signal "TOP")
		(4 "In1.Cu" signal "L2GND")
		(6 "In2.Cu" signal "L3")
		(8 "In3.Cu" signal "L4GND")
		(10 "In4.Cu" signal "L5")
		(12 "In5.Cu" signal "L6GND")
		(14 "In6.Cu" signal "L7VCC")
		(16 "In7.Cu" signal "L8VCC")
		(18 "In8.Cu" signal "L9GND")
		(20 "In9.Cu" signal "L10")
		(22 "In10.Cu" signal "L11GND")
		(24 "In11.Cu" signal "L12")
		(26 "In12.Cu" signal "L13GND")
		(2 "B.Cu" signal "BOTTOM")
		(9 "F.Adhes" user "F.Adhesive")
		(11 "B.Adhes" user "B.Adhesive")
		(13 "F.Paste" user "Package Geometry/Pastemask Top")
		(15 "B.Paste" user "Package Geometry/Pastemask Bottom")
		(5 "F.SilkS" user "Ref Des/Silkscreen Top")
		(7 "B.SilkS" user "Ref Des/Silkscreen Bottom")
		(1 "F.Mask" user "Board Geometry/Soldermask Top")
		(3 "B.Mask" user "Board Geometry/Soldermask Bottom")
		(17 "Dwgs.User" user "User.Drawings")
		(19 "Cmts.User" user "User.Comments")
		(21 "Eco1.User" user "User.Eco1")
		(23 "Eco2.User" user "User.Eco2")
		(25 "Edge.Cuts" user "Board Geometry/Outline")
		(27 "Margin" user)
		(31 "F.CrtYd" user "Package Geometry/Place Bound Top")
		(29 "B.CrtYd" user "Package Geometry/Place Bound Bottom")
		(35 "F.Fab" user "Ref Des/Assembly Top")
		(33 "B.Fab" user "Ref Des/Assembly Bottom")
	)
	(footprint ""
		(layer "B.Cu")
		(at 351.507806 -60.368434)
		(property "Reference" "R2U27"
			(at 0 0 0)
			(layer "B.SilkS")
			(hide yes)
			(effects
				(font
					(size 1.27 1.27)
				)
				(justify mirror)
			)
		)
		(property "Value" ""
			(at 0 0 0)
			(layer "B.Fab")
			(effects
				(font
					(size 1.27 1.27)
				)
				(justify mirror)
			)
		)
		(duplicate_pad_numbers_are_jumpers no)
		(fp_poly
			(pts
				(xy 0.2794 -0.1016) (xy -0.2794 -0.1016) (xy -0.2794 0.9906) (xy 0.2794 0.9906)
			)
			(stroke
				(width 0)
				(type default)
			)
			(fill no)
			(layer "B.CrtYd")
		)
		(fp_line
			(start -0.2794 -0.1016)
			(end 0.2794 -0.1016)
			(stroke
				(width 0.1)
				(type default)
			)
			(layer "B.Fab")
		)
		(fp_line
			(start -0.2794 0.9906)
			(end -0.2794 -0.1016)
			(stroke
				(width 0.1)
				(type default)
			)
			(layer "B.Fab")
		)
		(fp_line
			(start 0.2794 -0.1016)
			(end 0.2794 0.9906)
			(stroke
				(width 0.1)
				(type default)
			)
			(layer "B.Fab")
		)
		(fp_line
			(start 0.2794 0.9906)
			(end -0.2794 0.9906)
			(stroke
				(width 0.1)
				(type default)
			)
			(layer "B.Fab")
		)
		(pad "1" smd rect
			(at 0 0 180)
			(size 0.508 0.508)
			(layers "B.Cu" "B.Mask" "B.Paste")
			(net "P3E_CPU0_PE1_SS_RXN<6>")
		)
		(pad "2" smd rect
			(at 0 0.889 180)
			(size 0.508 0.508)
			(layers "B.Cu" "B.Mask" "B.Paste")
			(net "P3E_CPU0_PE1_SS_R_RXN<6>")
		)
		(zone
			(layer "B.Cu")
			(hatch none 0.5)
			(connect_pads
				(clearance 0)
			)
			(min_thickness 0.25)
			(keepout
				(tracks allowed)
				(vias not_allowed)
				(pads allowed)
				(copperpour not_allowed)
				(footprints allowed)
			)
			(placement
				(enabled no)
				(sheetname "")
			)
			(fill
				(thermal_gap 0.5)
				(thermal_bridge_width 0.5)
				(island_removal_mode 0)
			)
			(polygon
				(pts
					(xy 351.761806 -60.114434) (xy 351.253806 -60.114434) (xy 351.253806 -59.733434) (xy 351.761806 -59.733434)
				)
			)
		)
		(zone
			(layer "B.Cu")
			(hatch none 0.5)
			(connect_pads
				(clearance 0)
			)
			(min_thickness 0.25)
			(keepout
				(tracks not_allowed)
				(vias allowed)
				(pads allowed)
				(copperpour not_allowed)
				(footprints allowed)
			)
			(placement
				(enabled no)
				(sheetname "")
			)
			(fill
				(thermal_gap 0.5)
				(thermal_bridge_width 0.5)
				(island_removal_mode 0)
			)
			(polygon
				(pts
					(xy 351.761806 -59.733434) (xy 351.253806 -59.733434) (xy 351.253806 -60.114434) (xy 351.761806 -60.114434)
				)
			)
		)
	)
	(footprint ""
		(layer "B.Cu")
		(at 470.8144 -15.3162)
		(property "Reference" "C2U19"
			(at 0 0 0)
			(layer "B.SilkS")
			(hide yes)
			(effects
				(font
					(size 1.27 1.27)
				)
				(justify mirror)
			)
		)
		(property "Value" ""
			(at 0 0 0)
			(layer "B.Fab")
			(effects
				(font
					(size 1.27 1.27)
				)
				(justify mirror)
			)
		)
		(duplicate_pad_numbers_are_jumpers no)
		(fp_rect
			(start 0.3048 -0.1016)
			(end -0.3048 0.9906)
			(stroke
				(width 0)
				(type default)
			)
			(fill no)
			(layer "B.CrtYd")
		)
		(fp_line
			(start -0.3048 -0.1016)
			(end 0.3048 -0.1016)
			(stroke
				(width 0.1)
				(type default)
			)
			(layer "B.Fab")
		)
		(fp_line
			(start -0.3048 0.9906)
			(end -0.3048 -0.1016)
			(stroke
				(width 0.1)
				(type default)
			)
			(layer "B.Fab")
		)
		(fp_line
			(start 0.3048 -0.1016)
			(end 0.3048 0.9906)
			(stroke
				(width 0.1)
				(type default)
			)
			(layer "B.Fab")
		)
		(fp_line
			(start 0.3048 0.9906)
			(end -0.3048 0.9906)
			(stroke
				(width 0.1)
				(type default)
			)
			(layer "B.Fab")
		)
		(pad "1" smd rect
			(at 0 0 180)
			(size 0.508 0.508)
			(layers "B.Cu" "B.Mask" "B.Paste")
			(net "P3V3")
		)
		(pad "2" smd rect
			(at 0 0.889 180)
			(size 0.508 0.508)
			(layers "B.Cu" "B.Mask" "B.Paste")
			(net "GND")
		)
		(zone
			(layer "B.Cu")
			(hatch none 0.5)
			(connect_pads
				(clearance 0)
			)
			(min_thickness 0.25)
			(keepout
				(tracks not_allowed)
				(vias allowed)
				(pads allowed)
				(copperpour not_allowed)
				(footprints allowed)
			)
			(placement
				(enabled no)
				(sheetname "")
			)
			(fill
				(thermal_gap 0.5)
				(thermal_bridge_width 0.5)
				(island_removal_mode 0)
			)
			(polygon
				(pts
					(xy 471.0684 -15.0622) (xy 470.5604 -15.0622) (xy 470.5604 -14.6812) (xy 471.0684 -14.6812)
				)
			)
		)
		(zone
			(layer "B.Cu")
			(hatch none 0.5)
			(connect_pads
				(clearance 0)
			)
			(min_thickness 0.25)
			(keepout
				(tracks allowed)
				(vias not_allowed)
				(pads allowed)
				(copperpour not_allowed)
				(footprints allowed)
			)
			(placement
				(enabled no)
				(sheetname "")
			)
			(fill
				(thermal_gap 0.5)
				(thermal_bridge_width 0.5)
				(island_removal_mode 0)
			)
			(polygon
				(pts
					(xy 471.0684 -15.0622) (xy 470.5604 -15.0622) (xy 470.5604 -14.6812) (xy 471.0684 -14.6812)
				)
			)
		)
	)
)
